(kicad_pcb
	(version 20260206)
	(generator "pcbnew")
	(generator_version "10.0")
	(general
		(thickness 1.6)
		(legacy_teardrops no)
	)
	(paper "A4")
	(title_block
		(title "01162023_DA0F0TEBIF0_F0T_Expander_BD_F_brd_V02_OCP.brd")
		(comment 1 "Grand Teton / footprints 185-191 of 9728")
	)
	(layers
		(0 "F.Cu" signal "TOP")
		(4 "In1.Cu" signal "GND")
		(6 "In2.Cu" signal "VCC")
		(8 "In3.Cu" signal "VCC1")
		(10 "In4.Cu" signal "GND1")
		(12 "In5.Cu" signal "IN1")
		(14 "In6.Cu" signal "GND2")
		(16 "In7.Cu" signal "IN2")
		(18 "In8.Cu" signal "GND3")
		(20 "In9.Cu" signal "IN3")
		(22 "In10.Cu" signal "GND4")
		(24 "In11.Cu" signal "IN4")
		(26 "In12.Cu" signal "GND5")
		(28 "In13.Cu" signal "IN5")
		(30 "In14.Cu" signal "GND6")
		(32 "In15.Cu" signal "IN6")
		(34 "In16.Cu" signal "GND7")
		(2 "B.Cu" signal "BOTTOM")
		(9 "F.Adhes" user "F.Adhesive")
		(11 "B.Adhes" user "B.Adhesive")
		(13 "F.Paste" user "Package Geometry/Pastemask Top")
		(15 "B.Paste" user "Package Geometry/Pastemask Bottom")
		(5 "F.SilkS" user "Ref Des/Silkscreen Top")
		(7 "B.SilkS" user "Ref Des/Silkscreen Bottom")
		(1 "F.Mask" user "Board Geometry/Soldermask Top")
		(3 "B.Mask" user "Board Geometry/Soldermask Bottom")
		(17 "Dwgs.User" user "User.Drawings")
		(19 "Cmts.User" user "User.Comments")
		(21 "Eco1.User" user "User.Eco1")
		(23 "Eco2.User" user "User.Eco2")
		(25 "Edge.Cuts" user "Board Geometry/Outline")
		(27 "Margin" user)
		(31 "F.CrtYd" user "Package Geometry/Place Bound Top")
		(29 "B.CrtYd" user "Package Geometry/Place Bound Bottom")
		(35 "F.Fab" user "Ref Des/Assembly Top")
		(33 "B.Fab" user "Ref Des/Assembly Bottom")
	)
	(footprint ""
		(layer "F.Cu")
		(at 136.759696 -61.612526)
		(property "Reference" "PD16"
			(at -3.7084 -2.733548 0)
			(unlocked yes)
			(layer "F.SilkS")
			(effects
				(font
					(size 0.7874 0.5842)
					(thickness 0.1524)
				)
				(justify left)
			)
		)
		(property "Value" ""
			(at 0 0 0)
			(layer "F.Fab")
			(effects
				(font
					(size 1.27 1.27)
				)
			)
		)
		(duplicate_pad_numbers_are_jumpers no)
		(fp_line
			(start -3.656584 -1.970024)
			(end -3.656584 1.970024)
			(stroke
				(width 0.1524)
				(type default)
			)
			(layer "F.SilkS")
		)
		(fp_line
			(start -3.656584 1.970024)
			(end 4.240784 1.970024)
			(stroke
				(width 0.1524)
				(type default)
			)
			(layer "F.SilkS")
		)
		(fp_line
			(start 4.240784 -1.970024)
			(end -3.656584 -1.970024)
			(stroke
				(width 0.1524)
				(type default)
			)
			(layer "F.SilkS")
		)
		(fp_line
			(start 4.240784 1.970024)
			(end 4.240784 -1.970024)
			(stroke
				(width 0.1524)
				(type default)
			)
			(layer "F.SilkS")
		)
		(fp_poly
			(pts
				(xy 3.580384 1.970024) (xy 3.580384 -1.970024) (xy 4.240784 -1.970024) (xy 4.240784 1.970024)
			)
			(stroke
				(width 0)
				(type default)
			)
			(fill yes)
			(layer "F.SilkS")
		)
		(fp_line
			(start -2.3749 -1.970024)
			(end -2.3749 1.970024)
			(stroke
				(width 0.1)
				(type default)
			)
			(layer "F.Fab")
		)
		(fp_line
			(start -2.3749 1.970024)
			(end 2.3749 1.970024)
			(stroke
				(width 0.1)
				(type default)
			)
			(layer "F.Fab")
		)
		(fp_line
			(start 2.3749 -1.970024)
			(end -2.3749 -1.970024)
			(stroke
				(width 0.1)
				(type default)
			)
			(layer "F.Fab")
		)
		(fp_line
			(start 2.3749 1.970024)
			(end 2.3749 -1.970024)
			(stroke
				(width 0.1)
				(type default)
			)
			(layer "F.Fab")
		)
		(fp_text user "+"
			(at -4.9784 -0.23495 0)
			(unlocked yes)
			(layer "F.Fab")
			(effects
				(font
					(size 1.905 1.4224)
					(thickness 0.1524)
				)
				(justify left)
			)
		)
		(fp_text user "-"
			(at 4.1656 -0.23495 0)
			(unlocked yes)
			(layer "F.Fab")
			(effects
				(font
					(size 1.905 1.4224)
					(thickness 0.1524)
				)
				(justify left)
			)
		)
		(pad "A" smd rect
			(at -2.450084 0)
			(size 2.159 2.2606)
			(layers "F.Cu" "F.Mask" "F.Paste")
			(net "GND")
		)
		(pad "C" smd rect
			(at 2.450084 0)
			(size 2.159 2.2606)
			(layers "F.Cu" "F.Mask" "F.Paste")
			(net "P12V_AUX")
		)
	)
	(footprint ""
		(layer "F.Cu")
		(at 39.280592 -132.215382)
		(property "Reference" "C37"
			(at 0 0 0)
			(layer "F.SilkS")
			(hide yes)
			(effects
				(font
					(size 1.27 1.27)
				)
			)
		)
		(property "Value" ""
			(at 0 0 0)
			(layer "F.Fab")
			(effects
				(font
					(size 1.27 1.27)
				)
			)
		)
		(duplicate_pad_numbers_are_jumpers no)
		(fp_line
			(start -0.299974 -0.150114)
			(end 0.299974 -0.150114)
			(stroke
				(width 0.1)
				(type default)
			)
			(layer "F.Fab")
		)
		(fp_line
			(start -0.299974 0.150114)
			(end -0.299974 -0.150114)
			(stroke
				(width 0.1)
				(type default)
			)
			(layer "F.Fab")
		)
		(fp_line
			(start 0.299974 -0.150114)
			(end 0.299974 0.150114)
			(stroke
				(width 0.1)
				(type default)
			)
			(layer "F.Fab")
		)
		(fp_line
			(start 0.299974 0.150114)
			(end -0.299974 0.150114)
			(stroke
				(width 0.1)
				(type default)
			)
			(layer "F.Fab")
		)
		(pad "1" smd rect
			(at -0.2667 0)
			(size 0.3048 0.381)
			(layers "F.Cu" "F.Mask" "F.Paste")
			(net "P5E_PEX0_STN1_TX_DN<29>")
		)
		(pad "2" smd rect
			(at 0.2667 0)
			(size 0.3048 0.381)
			(layers "F.Cu" "F.Mask" "F.Paste")
			(net "P5E_PEX0_STN1_TX_C_DN<29>")
		)
	)
	(footprint ""
		(layer "F.Cu")
		(at 231.832404 -311.533032 90)
		(property "Reference" "R4436"
			(at 0 0 90)
			(layer "F.SilkS")
			(hide yes)
			(effects
				(font
					(size 1.27 1.27)
				)
			)
		)
		(property "Value" ""
			(at 0 0 90)
			(layer "F.Fab")
			(effects
				(font
					(size 1.27 1.27)
				)
			)
		)
		(duplicate_pad_numbers_are_jumpers no)
		(fp_line
			(start 0.7874 -0.4064)
			(end 0.7874 0.4064)
			(stroke
				(width 0.1524)
				(type default)
			)
			(layer "F.SilkS")
		)
		(fp_line
			(start -0.7874 -0.4064)
			(end 0.7874 -0.4064)
			(stroke
				(width 0.1524)
				(type default)
			)
			(layer "F.SilkS")
		)
		(fp_line
			(start 0.7874 0.4064)
			(end -0.7874 0.4064)
			(stroke
				(width 0.1524)
				(type default)
			)
			(layer "F.SilkS")
		)
		(fp_line
			(start -0.7874 0.4064)
			(end -0.7874 -0.4064)
			(stroke
				(width 0.1524)
				(type default)
			)
			(layer "F.SilkS")
		)
		(fp_line
			(start -0.12065 -0.305054)
			(end -0.12065 -0.2794)
			(stroke
				(width 0.1)
				(type default)
			)
			(layer "F.Fab")
		)
		(fp_line
			(start -0.67945 -0.305054)
			(end -0.12065 -0.305054)
			(stroke
				(width 0.1)
				(type default)
			)
			(layer "F.Fab")
		)
		(fp_line
			(start 0.67945 -0.3048)
			(end 0.67945 0.3048)
			(stroke
				(width 0.1)
				(type default)
			)
			(layer "F.Fab")
		)
		(fp_line
			(start 0.12065 -0.3048)
			(end 0.67945 -0.3048)
			(stroke
				(width 0.1)
				(type default)
			)
			(layer "F.Fab")
		)
		(fp_line
			(start 0.12065 -0.2794)
			(end 0.12065 -0.3048)
			(stroke
				(width 0.1)
				(type default)
			)
			(layer "F.Fab")
		)
		(fp_line
			(start -0.12065 -0.2794)
			(end 0.12065 -0.2794)
			(stroke
				(width 0.1)
				(type default)
			)
			(layer "F.Fab")
		)
		(fp_line
			(start 0.120396 0.2794)
			(end -0.12065 0.2794)
			(stroke
				(width 0.1)
				(type default)
			)
			(layer "F.Fab")
		)
		(fp_line
			(start -0.12065 0.2794)
			(end -0.12065 0.3048)
			(stroke
				(width 0.1)
				(type default)
			)
			(layer "F.Fab")
		)
		(fp_line
			(start 0.67945 0.3048)
			(end 0.120396 0.3048)
			(stroke
				(width 0.1)
				(type default)
			)
			(layer "F.Fab")
		)
		(fp_line
			(start 0.120396 0.3048)
			(end 0.120396 0.2794)
			(stroke
				(width 0.1)
				(type default)
			)
			(layer "F.Fab")
		)
		(fp_line
			(start -0.12065 0.3048)
			(end -0.67945 0.3048)
			(stroke
				(width 0.1)
				(type default)
			)
			(layer "F.Fab")
		)
		(fp_line
			(start -0.67945 0.3048)
			(end -0.67945 -0.305054)
			(stroke
				(width 0.1)
				(type default)
			)
			(layer "F.Fab")
		)
		(pad "1" smd circle
			(at -0.40005 0 90)
			(size 0 0)
			(layers "F.Cu" "F.Mask" "F.Paste")
			(net "PWRGD_P1V25_PEX1_R")
		)
		(pad "2" smd circle
			(at 0.40005 0 90)
			(size 0 0)
			(layers "F.Cu" "F.Mask" "F.Paste")
			(net "PWRGD_P1V25_PEX1")
		)
	)
	(footprint ""
		(layer "F.Cu")
		(at 379.279912 -310.28894 -135)
		(property "Reference" "R1400"
			(at 0 0 225)
			(layer "F.SilkS")
			(hide yes)
			(effects
				(font
					(size 1.27 1.27)
				)
			)
		)
		(property "Value" ""
			(at 0 0 225)
			(layer "F.Fab")
			(effects
				(font
					(size 1.27 1.27)
				)
			)
		)
		(duplicate_pad_numbers_are_jumpers no)
		(fp_line
			(start 0.787389 0.406267)
			(end -0.787389 0.406267)
			(stroke
				(width 0.1524)
				(type default)
			)
			(layer "F.SilkS")
		)
		(fp_line
			(start 0.787389 -0.406267)
			(end 0.787389 0.406267)
			(stroke
				(width 0.1524)
				(type default)
			)
			(layer "F.SilkS")
		)
		(fp_line
			(start -0.787389 0.406267)
			(end -0.787389 -0.406267)
			(stroke
				(width 0.1524)
				(type default)
			)
			(layer "F.SilkS")
		)
		(fp_line
			(start -0.787389 -0.406267)
			(end 0.787389 -0.406267)
			(stroke
				(width 0.1524)
				(type default)
			)
			(layer "F.SilkS")
		)
		(fp_line
			(start 0.679446 0.30479)
			(end 0.120515 0.30479)
			(stroke
				(width 0.1)
				(type default)
			)
			(layer "F.Fab")
		)
		(fp_line
			(start 0.120515 0.30479)
			(end 0.120335 0.279466)
			(stroke
				(width 0.1)
				(type default)
			)
			(layer "F.Fab")
		)
		(fp_line
			(start 0.120335 0.279466)
			(end -0.120695 0.279466)
			(stroke
				(width 0.1)
				(type default)
			)
			(layer "F.Fab")
		)
		(fp_line
			(start 0.679446 -0.30479)
			(end 0.679446 0.30479)
			(stroke
				(width 0.1)
				(type default)
			)
			(layer "F.Fab")
		)
		(fp_line
			(start -0.120515 0.30479)
			(end -0.679446 0.30479)
			(stroke
				(width 0.1)
				(type default)
			)
			(layer "F.Fab")
		)
		(fp_line
			(start -0.120695 0.279466)
			(end -0.120515 0.30479)
			(stroke
				(width 0.1)
				(type default)
			)
			(layer "F.Fab")
		)
		(fp_line
			(start 0.120695 -0.279466)
			(end 0.120515 -0.30479)
			(stroke
				(width 0.1)
				(type default)
			)
			(layer "F.Fab")
		)
		(fp_line
			(start 0.120515 -0.30479)
			(end 0.679446 -0.30479)
			(stroke
				(width 0.1)
				(type default)
			)
			(layer "F.Fab")
		)
		(fp_line
			(start -0.679446 0.30479)
			(end -0.679446 -0.305149)
			(stroke
				(width 0.1)
				(type default)
			)
			(layer "F.Fab")
		)
		(fp_line
			(start -0.120695 -0.279466)
			(end 0.120695 -0.279466)
			(stroke
				(width 0.1)
				(type default)
			)
			(layer "F.Fab")
		)
		(fp_line
			(start -0.120695 -0.304969)
			(end -0.120695 -0.279466)
			(stroke
				(width 0.1)
				(type default)
			)
			(layer "F.Fab")
		)
		(fp_line
			(start -0.679446 -0.305149)
			(end -0.120695 -0.304969)
			(stroke
				(width 0.1)
				(type default)
			)
			(layer "F.Fab")
		)
		(pad "1" smd circle
			(at -0.40005 0 225)
			(size 0 0)
			(layers "F.Cu" "F.Mask" "F.Paste")
			(net "PEX3_DBG_MODE0")
		)
		(pad "2" smd circle
			(at 0.40005 0 225)
			(size 0 0)
			(layers "F.Cu" "F.Mask" "F.Paste")
			(net "P1V8_PEX")
		)
	)
	(footprint ""
		(layer "F.Cu")
		(at 381.786384 -252.356874 -90)
		(property "Reference" "R1422"
			(at 0 0 270)
			(layer "F.SilkS")
			(hide yes)
			(effects
				(font
					(size 1.27 1.27)
				)
			)
		)
		(property "Value" ""
			(at 0 0 270)
			(layer "F.Fab")
			(effects
				(font
					(size 1.27 1.27)
				)
			)
		)
		(duplicate_pad_numbers_are_jumpers no)
		(fp_line
			(start -0.7874 0.4064)
			(end -0.7874 -0.4064)
			(stroke
				(width 0.1524)
				(type default)
			)
			(layer "F.SilkS")
		)
		(fp_line
			(start 0.7874 0.4064)
			(end -0.7874 0.4064)
			(stroke
				(width 0.1524)
				(type default)
			)
			(layer "F.SilkS")
		)
		(fp_line
			(start -0.7874 -0.4064)
			(end 0.7874 -0.4064)
			(stroke
				(width 0.1524)
				(type default)
			)
			(layer "F.SilkS")
		)
		(fp_line
			(start 0.7874 -0.4064)
			(end 0.7874 0.4064)
			(stroke
				(width 0.1524)
				(type default)
			)
			(layer "F.SilkS")
		)
		(fp_line
			(start -0.67945 0.3048)
			(end -0.67945 -0.305054)
			(stroke
				(width 0.1)
				(type default)
			)
			(layer "F.Fab")
		)
		(fp_line
			(start -0.12065 0.3048)
			(end -0.67945 0.3048)
			(stroke
				(width 0.1)
				(type default)
			)
			(layer "F.Fab")
		)
		(fp_line
			(start 0.120396 0.3048)
			(end 0.120396 0.2794)
			(stroke
				(width 0.1)
				(type default)
			)
			(layer "F.Fab")
		)
		(fp_line
			(start 0.67945 0.3048)
			(end 0.120396 0.3048)
			(stroke
				(width 0.1)
				(type default)
			)
			(layer "F.Fab")
		)
		(fp_line
			(start -0.12065 0.2794)
			(end -0.12065 0.3048)
			(stroke
				(width 0.1)
				(type default)
			)
			(layer "F.Fab")
		)
		(fp_line
			(start 0.120396 0.2794)
			(end -0.12065 0.2794)
			(stroke
				(width 0.1)
				(type default)
			)
			(layer "F.Fab")
		)
		(fp_line
			(start -0.12065 -0.2794)
			(end 0.12065 -0.2794)
			(stroke
				(width 0.1)
				(type default)
			)
			(layer "F.Fab")
		)
		(fp_line
			(start 0.12065 -0.2794)
			(end 0.12065 -0.3048)
			(stroke
				(width 0.1)
				(type default)
			)
			(layer "F.Fab")
		)
		(fp_line
			(start 0.12065 -0.3048)
			(end 0.67945 -0.3048)
			(stroke
				(width 0.1)
				(type default)
			)
			(layer "F.Fab")
		)
		(fp_line
			(start 0.67945 -0.3048)
			(end 0.67945 0.3048)
			(stroke
				(width 0.1)
				(type default)
			)
			(layer "F.Fab")
		)
		(fp_line
			(start -0.67945 -0.305054)
			(end -0.12065 -0.305054)
			(stroke
				(width 0.1)
				(type default)
			)
			(layer "F.Fab")
		)
		(fp_line
			(start -0.12065 -0.305054)
			(end -0.12065 -0.2794)
			(stroke
				(width 0.1)
				(type default)
			)
			(layer "F.Fab")
		)
		(pad "1" smd circle
			(at -0.40005 0 270)
			(size 0 0)
			(layers "F.Cu" "F.Mask" "F.Paste")
			(net "GND")
		)
		(pad "2" smd circle
			(at 0.40005 0 270)
			(size 0 0)
			(layers "F.Cu" "F.Mask" "F.Paste")
			(net "PEX3_DBG_MODE2")
		)
	)
	(footprint ""
		(layer "F.Cu")
		(at 346.782136 -38.041072 180)
		(property "Reference" "R6108"
			(at 0 0 180)
			(layer "F.SilkS")
			(hide yes)
			(effects
				(font
					(size 1.27 1.27)
				)
			)
		)
		(property "Value" ""
			(at 0 0 180)
			(layer "F.Fab")
			(effects
				(font
					(size 1.27 1.27)
				)
			)
		)
		(duplicate_pad_numbers_are_jumpers no)
		(fp_line
			(start 0.7874 0.4064)
			(end -0.7874 0.4064)
			(stroke
				(width 0.1524)
				(type default)
			)
			(layer "F.SilkS")
		)
		(fp_line
			(start 0.7874 -0.4064)
			(end 0.7874 0.4064)
			(stroke
				(width 0.1524)
				(type default)
			)
			(layer "F.SilkS")
		)
		(fp_line
			(start -0.7874 0.4064)
			(end -0.7874 -0.4064)
			(stroke
				(width 0.1524)
				(type default)
			)
			(layer "F.SilkS")
		)
		(fp_line
			(start -0.7874 -0.4064)
			(end 0.7874 -0.4064)
			(stroke
				(width 0.1524)
				(type default)
			)
			(layer "F.SilkS")
		)
		(fp_line
			(start 0.67945 0.3048)
			(end 0.120396 0.3048)
			(stroke
				(width 0.1)
				(type default)
			)
			(layer "F.Fab")
		)
		(fp_line
			(start 0.67945 -0.3048)
			(end 0.67945 0.3048)
			(stroke
				(width 0.1)
				(type default)
			)
			(layer "F.Fab")
		)
		(fp_line
			(start 0.12065 -0.2794)
			(end 0.12065 -0.3048)
			(stroke
				(width 0.1)
				(type default)
			)
			(layer "F.Fab")
		)
		(fp_line
			(start 0.12065 -0.3048)
			(end 0.67945 -0.3048)
			(stroke
				(width 0.1)
				(type default)
			)
			(layer "F.Fab")
		)
		(fp_line
			(start 0.120396 0.3048)
			(end 0.120396 0.2794)
			(stroke
				(width 0.1)
				(type default)
			)
			(layer "F.Fab")
		)
		(fp_line
			(start 0.120396 0.2794)
			(end -0.12065 0.2794)
			(stroke
				(width 0.1)
				(type default)
			)
			(layer "F.Fab")
		)
		(fp_line
			(start -0.12065 0.3048)
			(end -0.67945 0.3048)
			(stroke
				(width 0.1)
				(type default)
			)
			(layer "F.Fab")
		)
		(fp_line
			(start -0.12065 0.2794)
			(end -0.12065 0.3048)
			(stroke
				(width 0.1)
				(type default)
			)
			(layer "F.Fab")
		)
		(fp_line
			(start -0.12065 -0.2794)
			(end 0.12065 -0.2794)
			(stroke
				(width 0.1)
				(type default)
			)
			(layer "F.Fab")
		)
		(fp_line
			(start -0.12065 -0.305054)
			(end -0.12065 -0.2794)
			(stroke
				(width 0.1)
				(type default)
			)
			(layer "F.Fab")
		)
		(fp_line
			(start -0.67945 0.3048)
			(end -0.67945 -0.305054)
			(stroke
				(width 0.1)
				(type default)
			)
			(layer "F.Fab")
		)
		(fp_line
			(start -0.67945 -0.305054)
			(end -0.12065 -0.305054)
			(stroke
				(width 0.1)
				(type default)
			)
			(layer "F.Fab")
		)
		(pad "1" smd circle
			(at -0.40005 0 180)
			(size 0 0)
			(layers "F.Cu" "F.Mask" "F.Paste")
			(net "P5V_AUX")
		)
		(pad "2" smd circle
			(at 0.40005 0 180)
			(size 0 0)
			(layers "F.Cu" "F.Mask" "F.Paste")
			(net "P3V3_SSD12_PG_G2")
		)
	)
	(footprint ""
		(layer "F.Cu")
		(at 375.230136 -294.005508 -90)
		(property "Reference" "C3541"
			(at 0 0 270)
			(layer "F.SilkS")
			(hide yes)
			(effects
				(font
					(size 1.27 1.27)
				)
			)
		)
		(property "Value" ""
			(at 0 0 270)
			(layer "F.Fab")
			(effects
				(font
					(size 1.27 1.27)
				)
			)
		)
		(duplicate_pad_numbers_are_jumpers no)
		(fp_line
			(start -1.2954 0.5842)
			(end -1.2954 -0.5842)
			(stroke
				(width 0.1524)
				(type default)
			)
			(layer "F.SilkS")
		)
		(fp_line
			(start 1.2954 0.5842)
			(end -1.2954 0.5842)
			(stroke
				(width 0.1524)
				(type default)
			)
			(layer "F.SilkS")
		)
		(fp_line
			(start -1.2954 -0.5842)
			(end 1.2954 -0.5842)
			(stroke
				(width 0.1524)
				(type default)
			)
			(layer "F.SilkS")
		)
		(fp_line
			(start 1.2954 -0.5842)
			(end 1.2954 0.5842)
			(stroke
				(width 0.1524)
				(type default)
			)
			(layer "F.SilkS")
		)
		(fp_line
			(start -0.8636 0.4572)
			(end -0.8636 0.4064)
			(stroke
				(width 0.1)
				(type default)
			)
			(layer "F.Fab")
		)
		(fp_line
			(start 0.8636 0.4572)
			(end -0.8636 0.4572)
			(stroke
				(width 0.1)
				(type default)
			)
			(layer "F.Fab")
		)
		(fp_line
			(start -1.1938 0.4064)
			(end -1.1938 -0.4064)
			(stroke
				(width 0.1)
				(type default)
			)
			(layer "F.Fab")
		)
		(fp_line
			(start -0.8636 0.4064)
			(end -1.1938 0.4064)
			(stroke
				(width 0.1)
				(type default)
			)
			(layer "F.Fab")
		)
		(fp_line
			(start 0.8636 0.4064)
			(end 0.8636 0.4572)
			(stroke
				(width 0.1)
				(type default)
			)
			(layer "F.Fab")
		)
		(fp_line
			(start 1.1938 0.4064)
			(end 0.8636 0.4064)
			(stroke
				(width 0.1)
				(type default)
			)
			(layer "F.Fab")
		)
		(fp_line
			(start -1.1938 -0.4064)
			(end -0.8636 -0.4064)
			(stroke
				(width 0.1)
				(type default)
			)
			(layer "F.Fab")
		)
		(fp_line
			(start -0.8636 -0.4064)
			(end -0.8636 -0.4572)
			(stroke
				(width 0.1)
				(type default)
			)
			(layer "F.Fab")
		)
		(fp_line
			(start 0.8636 -0.4064)
			(end 1.1938 -0.4064)
			(stroke
				(width 0.1)
				(type default)
			)
			(layer "F.Fab")
		)
		(fp_line
			(start 1.1938 -0.4064)
			(end 1.1938 0.4064)
			(stroke
				(width 0.1)
				(type default)
			)
			(layer "F.Fab")
		)
		(fp_line
			(start -0.8636 -0.4572)
			(end 0.8636 -0.4572)
			(stroke
				(width 0.1)
				(type default)
			)
			(layer "F.Fab")
		)
		(fp_line
			(start 0.8636 -0.4572)
			(end 0.8636 -0.4064)
			(stroke
				(width 0.1)
				(type default)
			)
			(layer "F.Fab")
		)
		(pad "1" smd rect
			(at -0.7366 0 180)
			(size 0.7112 0.8128)
			(layers "F.Cu" "F.Mask" "F.Paste")
			(net "P1V8_PLL0_PEX3")
		)
		(pad "2" smd rect
			(at 0.7366 0 180)
			(size 0.7112 0.8128)
			(layers "F.Cu" "F.Mask" "F.Paste")
			(net "GND")
		)
	)
)
